# S9S_MB_2U (Grand Teton) — schematic netlist excerpt (pin names and nets, part order shuffled) for the footprints in the layout excerpt that follows; sources: Cadence DE-HDL packaged netlist, KiCad conversion of 03242023_DA0F0TMBIJ0_F0T_Motherboard_J_brd_V01_OCP.brd

C2270  Q_CAP  1000PF 50V 5% EMPTY  pkg 0402  page 146 : A = PRSNT_CABLE_GPU_A1_ISO_N ; B = GND
PC1236  Q_CAP  100NF 50V 10% X7R  pkg C0402  page 263 : A = P1V8_PCH_AUX ; B = GND

(kicad_pcb
	(version 20260206)
	(generator "pcbnew")
	(generator_version "10.0")
	(general
		(thickness 1.6)
		(legacy_teardrops no)
	)
	(paper "A4")
	(title_block
		(title "03242023_DA0F0TMBIJ0_F0T_Motherboard_J_brd_V01_OCP.brd")
		(comment 1 "Grand Teton / footprints 1518-1519 of 6105")
	)
	(layers
		(0 "F.Cu" signal "TOP")
		(4 "In1.Cu" signal "GND")
		(6 "In2.Cu" signal "IN1")
		(8 "In3.Cu" signal "GND1")
		(10 "In4.Cu" signal "IN2")
		(12 "In5.Cu" signal "GND2")
		(14 "In6.Cu" signal "IN3")
		(16 "In7.Cu" signal "GND3")
		(18 "In8.Cu" signal "VCC")
		(20 "In9.Cu" signal "VCC1")
		(22 "In10.Cu" signal "GND4")
		(24 "In11.Cu" signal "IN4")
		(26 "In12.Cu" signal "GND5")
		(28 "In13.Cu" signal "IN5")
		(30 "In14.Cu" signal "GND6")
		(32 "In15.Cu" signal "IN6")
		(34 "In16.Cu" signal "GND7")
		(2 "B.Cu" signal "BOTTOM")
		(9 "F.Adhes" user "F.Adhesive")
		(11 "B.Adhes" user "B.Adhesive")
		(13 "F.Paste" user "Package Geometry/Pastemask Top")
		(15 "B.Paste" user "Package Geometry/Pastemask Bottom")
		(5 "F.SilkS" user "Ref Des/Silkscreen Top")
		(7 "B.SilkS" user "Ref Des/Silkscreen Bottom")
		(1 "F.Mask" user "Board Geometry/Soldermask Top")
		(3 "B.Mask" user "Board Geometry/Soldermask Bottom")
		(17 "Dwgs.User" user "User.Drawings")
		(19 "Cmts.User" user "User.Comments")
		(21 "Eco1.User" user "User.Eco1")
		(23 "Eco2.User" user "User.Eco2")
		(25 "Edge.Cuts" user "Board Geometry/Outline")
		(27 "Margin" user)
		(31 "F.CrtYd" user "Package Geometry/Place Bound Top")
		(29 "B.CrtYd" user "Package Geometry/Place Bound Bottom")
		(35 "F.Fab" user "Ref Des/Assembly Top")
		(33 "B.Fab" user "Ref Des/Assembly Bottom")
	)
	(footprint ""
		(layer "F.Cu")
		(at 376.658632 -71.489824)
		(property "Reference" "PC1236"
			(at 0 0 0)
			(layer "F.SilkS")
			(hide yes)
			(effects
				(font
					(size 1.27 1.27)
				)
			)
		)
		(property "Value" ""
			(at 0 0 0)
			(layer "F.Fab")
			(effects
				(font
					(size 1.27 1.27)
				)
			)
		)
		(duplicate_pad_numbers_are_jumpers no)
		(fp_line
			(start -0.7874 -0.4064)
			(end 0.7874 -0.4064)
			(stroke
				(width 0.1524)
				(type default)
			)
			(layer "F.SilkS")
		)
		(fp_line
			(start -0.7874 0.4064)
			(end -0.7874 -0.4064)
			(stroke
				(width 0.1524)
				(type default)
			)
			(layer "F.SilkS")
		)
		(fp_line
			(start 0.7874 -0.4064)
			(end 0.7874 0.4064)
			(stroke
				(width 0.1524)
				(type default)
			)
			(layer "F.SilkS")
		)
		(fp_line
			(start 0.7874 0.4064)
			(end -0.7874 0.4064)
			(stroke
				(width 0.1524)
				(type default)
			)
			(layer "F.SilkS")
		)
		(fp_line
			(start -0.67945 -0.305054)
			(end -0.12065 -0.305054)
			(stroke
				(width 0.1)
				(type default)
			)
			(layer "F.Fab")
		)
		(fp_line
			(start -0.67945 0.3048)
			(end -0.67945 -0.305054)
			(stroke
				(width 0.1)
				(type default)
			)
			(layer "F.Fab")
		)
		(fp_line
			(start -0.12065 -0.305054)
			(end -0.12065 -0.2794)
			(stroke
				(width 0.1)
				(type default)
			)
			(layer "F.Fab")
		)
		(fp_line
			(start -0.12065 -0.2794)
			(end 0.12065 -0.2794)
			(stroke
				(width 0.1)
				(type default)
			)
			(layer "F.Fab")
		)
		(fp_line
			(start -0.12065 0.2794)
			(end -0.12065 0.3048)
			(stroke
				(width 0.1)
				(type default)
			)
			(layer "F.Fab")
		)
		(fp_line
			(start -0.12065 0.3048)
			(end -0.67945 0.3048)
			(stroke
				(width 0.1)
				(type default)
			)
			(layer "F.Fab")
		)
		(fp_line
			(start 0.120396 0.2794)
			(end -0.12065 0.2794)
			(stroke
				(width 0.1)
				(type default)
			)
			(layer "F.Fab")
		)
		(fp_line
			(start 0.120396 0.3048)
			(end 0.120396 0.2794)
			(stroke
				(width 0.1)
				(type default)
			)
			(layer "F.Fab")
		)
		(fp_line
			(start 0.12065 -0.3048)
			(end 0.67945 -0.3048)
			(stroke
				(width 0.1)
				(type default)
			)
			(layer "F.Fab")
		)
		(fp_line
			(start 0.12065 -0.2794)
			(end 0.12065 -0.3048)
			(stroke
				(width 0.1)
				(type default)
			)
			(layer "F.Fab")
		)
		(fp_line
			(start 0.67945 -0.3048)
			(end 0.67945 0.3048)
			(stroke
				(width 0.1)
				(type default)
			)
			(layer "F.Fab")
		)
		(fp_line
			(start 0.67945 0.3048)
			(end 0.120396 0.3048)
			(stroke
				(width 0.1)
				(type default)
			)
			(layer "F.Fab")
		)
		(pad "1" smd circle
			(at -0.40005 0)
			(size 0 0)
			(layers "F.Cu" "F.Mask" "F.Paste")
			(net "P1V8_PCH_AUX")
		)
		(pad "2" smd circle
			(at 0.40005 0)
			(size 0 0)
			(layers "F.Cu" "F.Mask" "F.Paste")
			(net "GND")
		)
	)
	(footprint ""
		(layer "F.Cu")
		(at 295.86682 -419.02761 -90)
		(property "Reference" "C2270"
			(at 0 0 270)
			(layer "F.SilkS")
			(hide yes)
			(effects
				(font
					(size 1.27 1.27)
				)
			)
		)
		(property "Value" ""
			(at 0 0 270)
			(layer "F.Fab")
			(effects
				(font
					(size 1.27 1.27)
				)
			)
		)
		(duplicate_pad_numbers_are_jumpers no)
		(fp_line
			(start -0.7874 0.4064)
			(end -0.7874 -0.4064)
			(stroke
				(width 0.1524)
				(type default)
			)
			(layer "F.SilkS")
		)
		(fp_line
			(start 0.7874 0.4064)
			(end -0.7874 0.4064)
			(stroke
				(width 0.1524)
				(type default)
			)
			(layer "F.SilkS")
		)
		(fp_line
			(start -0.7874 -0.4064)
			(end 0.7874 -0.4064)
			(stroke
				(width 0.1524)
				(type default)
			)
			(layer "F.SilkS")
		)
		(fp_line
			(start 0.7874 -0.4064)
			(end 0.7874 0.4064)
			(stroke
				(width 0.1524)
				(type default)
			)
			(layer "F.SilkS")
		)
		(fp_line
			(start -0.67945 0.3048)
			(end -0.67945 -0.305054)
			(stroke
				(width 0.1)
				(type default)
			)
			(layer "F.Fab")
		)
		(fp_line
			(start -0.12065 0.3048)
			(end -0.67945 0.3048)
			(stroke
				(width 0.1)
				(type default)
			)
			(layer "F.Fab")
		)
		(fp_line
			(start 0.120396 0.3048)
			(end 0.120396 0.2794)
			(stroke
				(width 0.1)
				(type default)
			)
			(layer "F.Fab")
		)
		(fp_line
			(start 0.67945 0.3048)
			(end 0.120396 0.3048)
			(stroke
				(width 0.1)
				(type default)
			)
			(layer "F.Fab")
		)
		(fp_line
			(start -0.12065 0.2794)
			(end -0.12065 0.3048)
			(stroke
				(width 0.1)
				(type default)
			)
			(layer "F.Fab")
		)
		(fp_line
			(start 0.120396 0.2794)
			(end -0.12065 0.2794)
			(stroke
				(width 0.1)
				(type default)
			)
			(layer "F.Fab")
		)
		(fp_line
			(start -0.12065 -0.2794)
			(end 0.12065 -0.2794)
			(stroke
				(width 0.1)
				(type default)
			)
			(layer "F.Fab")
		)
		(fp_line
			(start 0.12065 -0.2794)
			(end 0.12065 -0.3048)
			(stroke
				(width 0.1)
				(type default)
			)
			(layer "F.Fab")
		)
		(fp_line
			(start 0.12065 -0.3048)
			(end 0.67945 -0.3048)
			(stroke
				(width 0.1)
				(type default)
			)
			(layer "F.Fab")
		)
		(fp_line
			(start 0.67945 -0.3048)
			(end 0.67945 0.3048)
			(stroke
				(width 0.1)
				(type default)
			)
			(layer "F.Fab")
		)
		(fp_line
			(start -0.67945 -0.305054)
			(end -0.12065 -0.305054)
			(stroke
				(width 0.1)
				(type default)
			)
			(layer "F.Fab")
		)
		(fp_line
			(start -0.12065 -0.305054)
			(end -0.12065 -0.2794)
			(stroke
				(width 0.1)
				(type default)
			)
			(layer "F.Fab")
		)
		(pad "1" smd circle
			(at -0.40005 0 270)
			(size 0 0)
			(layers "F.Cu" "F.Mask" "F.Paste")
			(net "PRSNT_CABLE_GPU_A1_ISO_N")
		)
		(pad "2" smd circle
			(at 0.40005 0 270)
			(size 0 0)
			(layers "F.Cu" "F.Mask" "F.Paste")
			(net "GND")
		)
	)
)
